# SCM (Grand Teton) — schematic netlist excerpt (pin names and nets, part order shuffled) for the footprints in the layout excerpt that follows; sources: Cadence DE-HDL packaged netlist, KiCad conversion of 12092022_DA0F0TMDCD0_F0T_Management_Board_D_brd_V3_OCP.brd

R710  Q_RES  100K 1% CHIP  pkg 0402LF  page 22 : A = P3V3_AUX ; B = U43_CT
R98  Q_RES  0 5% CHIP  pkg 0402LF  page 46 : A = SPI_BMC_TPM_MISO_R ; B = SPI_BMC_TPM_MISO
PC258  Q_CAP  22UF 4V 20% X6S  pkg 0805  page 55 : A = P1V2_AUX ; B = GND

(kicad_pcb
	(version 20260206)
	(generator "pcbnew")
	(generator_version "10.0")
	(general
		(thickness 1.6)
		(legacy_teardrops no)
	)
	(paper "A4")
	(title_block
		(title "12092022_DA0F0TMDCD0_F0T_Management_Board_D_brd_V3_OCP.brd")
		(comment 1 "Grand Teton / footprints 342-344 of 1440")
	)
	(layers
		(0 "F.Cu" signal "TOP")
		(4 "In1.Cu" signal "GND")
		(6 "In2.Cu" signal "IN1")
		(8 "In3.Cu" signal "GND1")
		(10 "In4.Cu" signal "IN2")
		(12 "In5.Cu" signal "VCC")
		(14 "In6.Cu" signal "VCC1")
		(16 "In7.Cu" signal "IN3")
		(18 "In8.Cu" signal "GND2")
		(20 "In9.Cu" signal "IN4")
		(22 "In10.Cu" signal "GND3")
		(2 "B.Cu" signal "BOTTOM")
		(9 "F.Adhes" user "F.Adhesive")
		(11 "B.Adhes" user "B.Adhesive")
		(13 "F.Paste" user "Package Geometry/Pastemask Top")
		(15 "B.Paste" user "Package Geometry/Pastemask Bottom")
		(5 "F.SilkS" user "Ref Des/Silkscreen Top")
		(7 "B.SilkS" user "Ref Des/Silkscreen Bottom")
		(1 "F.Mask" user "Board Geometry/Soldermask Top")
		(3 "B.Mask" user "Board Geometry/Soldermask Bottom")
		(17 "Dwgs.User" user "User.Drawings")
		(19 "Cmts.User" user "User.Comments")
		(21 "Eco1.User" user "User.Eco1")
		(23 "Eco2.User" user "User.Eco2")
		(25 "Edge.Cuts" user "Board Geometry/Outline")
		(27 "Margin" user)
		(31 "F.CrtYd" user "Package Geometry/Place Bound Top")
		(29 "B.CrtYd" user "Package Geometry/Place Bound Bottom")
		(35 "F.Fab" user "Ref Des/Assembly Top")
		(33 "B.Fab" user "Ref Des/Assembly Bottom")
	)
	(footprint ""
		(layer "F.Cu")
		(at 79.685134 -59.059826 -90)
		(property "Reference" "PC258"
			(at 0 0 270)
			(layer "F.SilkS")
			(hide yes)
			(effects
				(font
					(size 1.27 1.27)
				)
			)
		)
		(property "Value" ""
			(at 0 0 270)
			(layer "F.Fab")
			(effects
				(font
					(size 1.27 1.27)
				)
			)
		)
		(duplicate_pad_numbers_are_jumpers no)
		(fp_line
			(start -1.651 0.8382)
			(end -1.651 -0.8382)
			(stroke
				(width 0.1524)
				(type default)
			)
			(layer "F.SilkS")
		)
		(fp_line
			(start 0 0.8382)
			(end 0 -0.8382)
			(stroke
				(width 0.1524)
				(type default)
			)
			(layer "F.SilkS")
		)
		(fp_line
			(start 1.651 0.8382)
			(end -1.651 0.8382)
			(stroke
				(width 0.1524)
				(type default)
			)
			(layer "F.SilkS")
		)
		(fp_line
			(start -1.651 -0.8382)
			(end 1.651 -0.8382)
			(stroke
				(width 0.1524)
				(type default)
			)
			(layer "F.SilkS")
		)
		(fp_line
			(start 1.651 -0.8382)
			(end 1.651 0.8382)
			(stroke
				(width 0.1524)
				(type default)
			)
			(layer "F.SilkS")
		)
		(fp_line
			(start -1.55956 0.7366)
			(end -1.524 0.7366)
			(stroke
				(width 0.1)
				(type default)
			)
			(layer "F.Fab")
		)
		(fp_line
			(start -1.524 0.7366)
			(end 1.524 0.7366)
			(stroke
				(width 0.1)
				(type default)
			)
			(layer "F.Fab")
		)
		(fp_line
			(start 1.524 0.7366)
			(end 1.55956 0.7366)
			(stroke
				(width 0.1)
				(type default)
			)
			(layer "F.Fab")
		)
		(fp_line
			(start 1.55956 0.7366)
			(end 1.55956 -0.7366)
			(stroke
				(width 0.1)
				(type default)
			)
			(layer "F.Fab")
		)
		(fp_line
			(start -1.55956 -0.7366)
			(end -1.55956 0.7366)
			(stroke
				(width 0.1)
				(type default)
			)
			(layer "F.Fab")
		)
		(fp_line
			(start -1.524 -0.7366)
			(end -1.55956 -0.7366)
			(stroke
				(width 0.1)
				(type default)
			)
			(layer "F.Fab")
		)
		(fp_line
			(start 1.524 -0.7366)
			(end -1.524 -0.7366)
			(stroke
				(width 0.1)
				(type default)
			)
			(layer "F.Fab")
		)
		(fp_line
			(start 1.55956 -0.7366)
			(end 1.524 -0.7366)
			(stroke
				(width 0.1)
				(type default)
			)
			(layer "F.Fab")
		)
		(pad "1" smd rect
			(at -0.94996 0 90)
			(size 1.1176 1.3716)
			(layers "F.Cu" "F.Mask" "F.Paste")
			(net "P1V2_AUX")
		)
		(pad "2" smd rect
			(at 0.94996 0 90)
			(size 1.1176 1.3716)
			(layers "F.Cu" "F.Mask" "F.Paste")
			(net "GND")
		)
	)
	(footprint ""
		(layer "F.Cu")
		(at 36.068 -44.5008 180)
		(property "Reference" "R710"
			(at 0 0 180)
			(layer "F.SilkS")
			(hide yes)
			(effects
				(font
					(size 1.27 1.27)
				)
			)
		)
		(property "Value" ""
			(at 0 0 180)
			(layer "F.Fab")
			(effects
				(font
					(size 1.27 1.27)
				)
			)
		)
		(duplicate_pad_numbers_are_jumpers no)
		(fp_line
			(start 0.7874 0.4064)
			(end -0.7874 0.4064)
			(stroke
				(width 0.1524)
				(type default)
			)
			(layer "F.SilkS")
		)
		(fp_line
			(start 0.7874 -0.4064)
			(end 0.7874 0.4064)
			(stroke
				(width 0.1524)
				(type default)
			)
			(layer "F.SilkS")
		)
		(fp_line
			(start -0.7874 0.4064)
			(end -0.7874 -0.4064)
			(stroke
				(width 0.1524)
				(type default)
			)
			(layer "F.SilkS")
		)
		(fp_line
			(start -0.7874 -0.4064)
			(end 0.7874 -0.4064)
			(stroke
				(width 0.1524)
				(type default)
			)
			(layer "F.SilkS")
		)
		(fp_line
			(start 0.67945 0.3048)
			(end 0.120396 0.3048)
			(stroke
				(width 0.1)
				(type default)
			)
			(layer "F.Fab")
		)
		(fp_line
			(start 0.67945 -0.3048)
			(end 0.67945 0.3048)
			(stroke
				(width 0.1)
				(type default)
			)
			(layer "F.Fab")
		)
		(fp_line
			(start 0.12065 -0.2794)
			(end 0.12065 -0.3048)
			(stroke
				(width 0.1)
				(type default)
			)
			(layer "F.Fab")
		)
		(fp_line
			(start 0.12065 -0.3048)
			(end 0.67945 -0.3048)
			(stroke
				(width 0.1)
				(type default)
			)
			(layer "F.Fab")
		)
		(fp_line
			(start 0.120396 0.3048)
			(end 0.120396 0.2794)
			(stroke
				(width 0.1)
				(type default)
			)
			(layer "F.Fab")
		)
		(fp_line
			(start 0.120396 0.2794)
			(end -0.12065 0.2794)
			(stroke
				(width 0.1)
				(type default)
			)
			(layer "F.Fab")
		)
		(fp_line
			(start -0.12065 0.3048)
			(end -0.67945 0.3048)
			(stroke
				(width 0.1)
				(type default)
			)
			(layer "F.Fab")
		)
		(fp_line
			(start -0.12065 0.2794)
			(end -0.12065 0.3048)
			(stroke
				(width 0.1)
				(type default)
			)
			(layer "F.Fab")
		)
		(fp_line
			(start -0.12065 -0.2794)
			(end 0.12065 -0.2794)
			(stroke
				(width 0.1)
				(type default)
			)
			(layer "F.Fab")
		)
		(fp_line
			(start -0.12065 -0.305054)
			(end -0.12065 -0.2794)
			(stroke
				(width 0.1)
				(type default)
			)
			(layer "F.Fab")
		)
		(fp_line
			(start -0.67945 0.3048)
			(end -0.67945 -0.305054)
			(stroke
				(width 0.1)
				(type default)
			)
			(layer "F.Fab")
		)
		(fp_line
			(start -0.67945 -0.305054)
			(end -0.12065 -0.305054)
			(stroke
				(width 0.1)
				(type default)
			)
			(layer "F.Fab")
		)
		(pad "1" smd circle
			(at -0.40005 0 180)
			(size 0 0)
			(layers "F.Cu" "F.Mask" "F.Paste")
			(net "P3V3_AUX")
		)
		(pad "2" smd circle
			(at 0.40005 0 180)
			(size 0 0)
			(layers "F.Cu" "F.Mask" "F.Paste")
			(net "U43_CT")
		)
	)
	(footprint ""
		(layer "F.Cu")
		(at 84.201 -95.631)
		(property "Reference" "R98"
			(at 0 0 0)
			(layer "F.SilkS")
			(hide yes)
			(effects
				(font
					(size 1.27 1.27)
				)
			)
		)
		(property "Value" ""
			(at 0 0 0)
			(layer "F.Fab")
			(effects
				(font
					(size 1.27 1.27)
				)
			)
		)
		(duplicate_pad_numbers_are_jumpers no)
		(fp_line
			(start -0.7874 -0.4064)
			(end 0.7874 -0.4064)
			(stroke
				(width 0.1524)
				(type default)
			)
			(layer "F.SilkS")
		)
		(fp_line
			(start -0.7874 0.4064)
			(end -0.7874 -0.4064)
			(stroke
				(width 0.1524)
				(type default)
			)
			(layer "F.SilkS")
		)
		(fp_line
			(start 0.7874 -0.4064)
			(end 0.7874 0.4064)
			(stroke
				(width 0.1524)
				(type default)
			)
			(layer "F.SilkS")
		)
		(fp_line
			(start 0.7874 0.4064)
			(end -0.7874 0.4064)
			(stroke
				(width 0.1524)
				(type default)
			)
			(layer "F.SilkS")
		)
		(fp_line
			(start -0.67945 -0.305054)
			(end -0.12065 -0.305054)
			(stroke
				(width 0.1)
				(type default)
			)
			(layer "F.Fab")
		)
		(fp_line
			(start -0.67945 0.3048)
			(end -0.67945 -0.305054)
			(stroke
				(width 0.1)
				(type default)
			)
			(layer "F.Fab")
		)
		(fp_line
			(start -0.12065 -0.305054)
			(end -0.12065 -0.2794)
			(stroke
				(width 0.1)
				(type default)
			)
			(layer "F.Fab")
		)
		(fp_line
			(start -0.12065 -0.2794)
			(end 0.12065 -0.2794)
			(stroke
				(width 0.1)
				(type default)
			)
			(layer "F.Fab")
		)
		(fp_line
			(start -0.12065 0.2794)
			(end -0.12065 0.3048)
			(stroke
				(width 0.1)
				(type default)
			)
			(layer "F.Fab")
		)
		(fp_line
			(start -0.12065 0.3048)
			(end -0.67945 0.3048)
			(stroke
				(width 0.1)
				(type default)
			)
			(layer "F.Fab")
		)
		(fp_line
			(start 0.120396 0.2794)
			(end -0.12065 0.2794)
			(stroke
				(width 0.1)
				(type default)
			)
			(layer "F.Fab")
		)
		(fp_line
			(start 0.120396 0.3048)
			(end 0.120396 0.2794)
			(stroke
				(width 0.1)
				(type default)
			)
			(layer "F.Fab")
		)
		(fp_line
			(start 0.12065 -0.3048)
			(end 0.67945 -0.3048)
			(stroke
				(width 0.1)
				(type default)
			)
			(layer "F.Fab")
		)
		(fp_line
			(start 0.12065 -0.2794)
			(end 0.12065 -0.3048)
			(stroke
				(width 0.1)
				(type default)
			)
			(layer "F.Fab")
		)
		(fp_line
			(start 0.67945 -0.3048)
			(end 0.67945 0.3048)
			(stroke
				(width 0.1)
				(type default)
			)
			(layer "F.Fab")
		)
		(fp_line
			(start 0.67945 0.3048)
			(end 0.120396 0.3048)
			(stroke
				(width 0.1)
				(type default)
			)
			(layer "F.Fab")
		)
		(pad "1" smd circle
			(at -0.40005 0)
			(size 0 0)
			(layers "F.Cu" "F.Mask" "F.Paste")
			(net "SPI_BMC_TPM_MISO_R")
		)
		(pad "2" smd circle
			(at 0.40005 0)
			(size 0 0)
			(layers "F.Cu" "F.Mask" "F.Paste")
			(net "SPI_BMC_TPM_MISO")
		)
	)
)
